(kicad_pcb
	(version 20241229)
	(generator "pcbnew")
	(generator_version "9.0")
	(general
		(thickness 1.61)
		(legacy_teardrops no)
	)
	(paper "A3")
	(title_block
		(title "RDIMM DDR5 Tester")
		(date "2026-05-21")
		(rev "2.2.0")
		(company "Antmicro")
		(comment 9 "footprints 344-348 of 796")
	)
	(layers
		(0 "F.Cu" signal)
		(4 "In1.Cu" power)
		(6 "In2.Cu" mixed)
		(8 "In3.Cu" power)
		(10 "In4.Cu" mixed)
		(12 "In5.Cu" power)
		(14 "In6.Cu" mixed)
		(16 "In7.Cu" power)
		(18 "In8.Cu" power)
		(20 "In9.Cu" mixed)
		(22 "In10.Cu" power)
		(2 "B.Cu" signal)
		(9 "F.Adhes" user "F.Adhesive")
		(11 "B.Adhes" user "B.Adhesive")
		(13 "F.Paste" user)
		(15 "B.Paste" user)
		(5 "F.SilkS" user "F.Silkscreen")
		(7 "B.SilkS" user "B.Silkscreen")
		(1 "F.Mask" user)
		(3 "B.Mask" user)
		(17 "Dwgs.User" user "User.Drawings")
		(19 "Cmts.User" user "User.Comments")
		(21 "Eco1.User" user "User.Eco1")
		(23 "Eco2.User" user "User.Eco2")
		(25 "Edge.Cuts" user)
		(27 "Margin" user)
		(31 "F.CrtYd" user "F.Courtyard")
		(29 "B.CrtYd" user "B.Courtyard")
		(35 "F.Fab" user)
		(33 "B.Fab" user)
	)
	(footprint "antmicro-footprints:R_0402_1005Metric"
		(layer "F.Cu")
		(at 254.02 177.6095 180)
		(descr "Resistor SMD 0402")
		(tags "resistor SMD 0402")
		(property "Reference" "R152"
			(at 0.57 -1.4905 0)
			(layer "F.SilkS")
			(effects
				(font
					(size 0.7 0.7)
					(thickness 0.15)
				)
				(justify right bottom)
			)
		)
		(property "Value" "R_0R_0402"
			(at -1.011843 1.772047 0)
			(layer "F.Fab")
			(effects
				(font
					(size 0.7 0.7)
					(thickness 0.15)
				)
				(justify right bottom)
			)
		)
		(property "Datasheet" "https://industrial.panasonic.com/cdbs/www-data/pdf/RDA0000/AOA0000C301.pdf"
			(at 0 0 180)
			(layer "F.Fab")
			(hide yes)
			(effects
				(font
					(size 1.27 1.27)
					(thickness 0.15)
				)
			)
		)
		(property "Manufacturer" "Panasonic"
			(at 0 0 180)
			(unlocked yes)
			(layer "F.Fab")
			(hide yes)
			(effects
				(font
					(size 1 1)
					(thickness 0.15)
				)
			)
		)
		(property "MPN" "ERJ2GE0R00X"
			(at 0 0 180)
			(unlocked yes)
			(layer "F.Fab")
			(hide yes)
			(effects
				(font
					(size 1 1)
					(thickness 0.15)
				)
			)
		)
		(property "Val" "0R"
			(at 0 0 180)
			(unlocked yes)
			(layer "F.Fab")
			(hide yes)
			(effects
				(font
					(size 1 1)
					(thickness 0.15)
				)
			)
		)
		(property "License" "Apache-2.0"
			(at 0 0 180)
			(unlocked yes)
			(layer "F.Fab")
			(hide yes)
			(effects
				(font
					(size 1 1)
					(thickness 0.15)
				)
			)
		)
		(property "Author" "Antmicro"
			(at 0 0 180)
			(unlocked yes)
			(layer "F.Fab")
			(hide yes)
			(effects
				(font
					(size 1 1)
					(thickness 0.15)
				)
			)
		)
		(property "Tolerance" "~"
			(at 0 0 180)
			(unlocked yes)
			(layer "F.Fab")
			(hide yes)
			(effects
				(font
					(size 1 1)
					(thickness 0.15)
				)
			)
		)
		(property "Current" "1A"
			(at 0 0 180)
			(unlocked yes)
			(layer "F.Fab")
			(hide yes)
			(effects
				(font
					(size 1 1)
					(thickness 0.15)
				)
			)
		)
		(sheetname "/Supply/DC-DC AUX, MGT/")
		(sheetfile "dc-dc-aux-mgt.kicad_sch")
		(attr smd)
		(fp_rect
			(start -0.925 -0.47)
			(end 0.925 0.47)
			(stroke
				(width 0.05)
				(type default)
			)
			(fill no)
			(layer "F.CrtYd")
		)
		(fp_rect
			(start -0.5 -0.25)
			(end 0.5 0.25)
			(stroke
				(width 0.15)
				(type solid)
			)
			(fill no)
			(layer "F.Fab")
		)
		(fp_text user "${REFERENCE}"
			(at -0.95 3.168 180)
			(layer "F.Fab")
			(effects
				(font
					(size 0.7 0.7)
					(thickness 0.15)
				)
				(justify left bottom)
			)
		)
		(fp_text user "License: Apache-2.0"
			(at -0.95 5.169 180)
			(layer "F.Fab")
			(effects
				(font
					(size 0.7 0.7)
					(thickness 0.15)
				)
				(justify left bottom)
			)
		)
		(fp_text user "Author: Antmicro"
			(at -0.95 4.169 180)
			(layer "F.Fab")
			(effects
				(font
					(size 0.7 0.7)
					(thickness 0.15)
				)
				(justify left bottom)
			)
		)
		(pad "1" smd roundrect
			(at -0.48 0 180)
			(size 0.59 0.64)
			(layers "F.Cu" "F.Mask" "F.Paste")
			(roundrect_rratio 0.25)
			(net 712 "/Supply/DC-DC AUX, MGT/FB1")
			(pintype "passive")
		)
		(pad "2" smd roundrect
			(at 0.48 0 180)
			(size 0.59 0.64)
			(layers "F.Cu" "F.Mask" "F.Paste")
			(roundrect_rratio 0.25)
			(net 37 "/Supply/DC-DC AUX, MGT/1V8_local")
			(pintype "passive")
		)
	)
	(footprint "antmicro-footprints:SOT-23-6"
		(layer "F.Cu")
		(at 242.447 126.6561 180)
		(property "Reference" "U17"
			(at 1.666258 1.3561 90)
			(layer "F.SilkS")
			(effects
				(font
					(size 0.7 0.7)
					(thickness 0.15)
				)
				(justify right bottom)
			)
		)
		(property "Value" "LTC4412IS6"
			(at -1.75 2.75 0)
			(layer "F.Fab")
			(effects
				(font
					(size 0.7 0.7)
					(thickness 0.15)
				)
				(justify right bottom)
			)
		)
		(property "Datasheet" "https://www.mouser.com/datasheet/2/308/NCV8187_D-1813214.pdf"
			(at 0 0 180)
			(layer "F.Fab")
			(hide yes)
			(effects
				(font
					(size 1.27 1.27)
					(thickness 0.15)
				)
			)
		)
		(property "MPN" "LTC4412IS6#TRMPBF"
			(at 0 0 180)
			(unlocked yes)
			(layer "F.Fab")
			(hide yes)
			(effects
				(font
					(size 1 1)
					(thickness 0.15)
				)
			)
		)
		(property "Manufacturer" "Analog Devices"
			(at 0 0 180)
			(unlocked yes)
			(layer "F.Fab")
			(hide yes)
			(effects
				(font
					(size 1 1)
					(thickness 0.15)
				)
			)
		)
		(property "Author" "Antmicro"
			(at 0 0 180)
			(unlocked yes)
			(layer "F.Fab")
			(hide yes)
			(effects
				(font
					(size 1 1)
					(thickness 0.15)
				)
			)
		)
		(property "License" "Apache-2.0"
			(at 0 0 180)
			(unlocked yes)
			(layer "F.Fab")
			(hide yes)
			(effects
				(font
					(size 1 1)
					(thickness 0.15)
				)
			)
		)
		(sheetname "/Supply/")
		(sheetfile "supply.kicad_sch")
		(attr smd)
		(fp_line
			(start 1.45 0.643)
			(end 1.45 0.343)
			(stroke
				(width 0.12)
				(type solid)
			)
			(layer "F.SilkS")
		)
		(fp_line
			(start 1.45 -0.757)
			(end 1.45 -0.457)
			(stroke
				(width 0.12)
				(type solid)
			)
			(layer "F.SilkS")
		)
		(fp_line
			(start 1.3 0.643)
			(end 1.45 0.643)
			(stroke
				(width 0.12)
				(type solid)
			)
			(layer "F.SilkS")
		)
		(fp_line
			(start 1.3 -0.757)
			(end 1.45 -0.757)
			(stroke
				(width 0.12)
				(type solid)
			)
			(layer "F.SilkS")
		)
		(fp_line
			(start -1.3 -0.757)
			(end -1.45 -0.757)
			(stroke
				(width 0.12)
				(type solid)
			)
			(layer "F.SilkS")
		)
		(fp_line
			(start -1.45 0.643)
			(end -1.45 0.343)
			(stroke
				(width 0.12)
				(type solid)
			)
			(layer "F.SilkS")
		)
		(fp_line
			(start -1.45 -0.757)
			(end -1.45 -0.457)
			(stroke
				(width 0.12)
				(type solid)
			)
			(layer "F.SilkS")
		)
		(fp_rect
			(start -1.55 -1.85)
			(end 1.55 1.75)
			(stroke
				(width 0.05)
				(type solid)
			)
			(fill no)
			(layer "F.CrtYd")
		)
		(fp_line
			(start 1.5 0.643)
			(end -1.5 0.643)
			(stroke
				(width 0.1)
				(type solid)
			)
			(layer "F.Fab")
		)
		(fp_line
			(start 1.5 -0.757)
			(end 1.5 0.643)
			(stroke
				(width 0.1)
				(type solid)
			)
			(layer "F.Fab")
		)
		(fp_line
			(start -1.5 0.643)
			(end -1.5 -0.757)
			(stroke
				(width 0.1)
				(type solid)
			)
			(layer "F.Fab")
		)
		(fp_line
			(start -1.5 -0.757)
			(end 1.5 -0.757)
			(stroke
				(width 0.1)
				(type solid)
			)
			(layer "F.Fab")
		)
		(fp_text user "."
			(at -1.4 1.2 0)
			(layer "F.SilkS")
			(effects
				(font
					(size 1 1)
					(thickness 0.15)
				)
			)
		)
		(fp_text user "Author: Antmicro"
			(at -1.829 5.25 180)
			(layer "F.Fab")
			(effects
				(font
					(size 0.7 0.7)
					(thickness 0.15)
				)
				(justify left bottom)
			)
		)
		(fp_text user "License: Apache-2.0"
			(at -1.75 6.5 180)
			(layer "F.Fab")
			(effects
				(font
					(size 0.7 0.7)
					(thickness 0.15)
				)
				(justify left bottom)
			)
		)
		(fp_text user "${REFERENCE}"
			(at -1.75 4 180)
			(layer "F.Fab")
			(effects
				(font
					(size 0.7 0.7)
					(thickness 0.15)
				)
				(justify left bottom)
			)
		)
		(pad "1" smd roundrect
			(at -0.954 1.1 180)
			(size 0.55 1)
			(layers "F.Cu" "F.Mask" "F.Paste")
			(roundrect_rratio 0.15)
			(net 323 "/Supply/12V_aux_fused")
			(pinfunction "IN")
			(pintype "power_in")
		)
		(pad "2" smd roundrect
			(at -0.003 1.1 180)
			(size 0.55 1)
			(layers "F.Cu" "F.Mask" "F.Paste")
			(roundrect_rratio 0.15)
			(net 1 "GND")
			(pinfunction "GND")
			(pintype "power_in")
		)
		(pad "3" smd roundrect
			(at 0.947 1.1 180)
			(size 0.55 1)
			(layers "F.Cu" "F.Mask" "F.Paste")
			(roundrect_rratio 0.15)
			(net 1 "GND")
			(pinfunction "CTL")
			(pintype "input")
		)
		(pad "4" smd roundrect
			(at 0.947 -1.214 180)
			(size 0.55 1)
			(layers "F.Cu" "F.Mask" "F.Paste")
			(roundrect_rratio 0.15)
			(net 428 "unconnected-(U17-STAT-Pad4)")
			(pinfunction "STAT")
			(pintype "output+no_connect")
		)
		(pad "5" smd roundrect
			(at -0.003 -1.214 180)
			(size 0.55 1)
			(layers "F.Cu" "F.Mask" "F.Paste")
			(roundrect_rratio 0.15)
			(net 284 "Net-(Q12-G)")
			(pinfunction "GATE")
			(pintype "output")
		)
		(pad "6" smd roundrect
			(at -0.954 -1.214 180)
			(size 0.55 1)
			(layers "F.Cu" "F.Mask" "F.Paste")
			(roundrect_rratio 0.15)
			(net 35 "VDC")
			(pinfunction "SENSE")
			(pintype "input")
		)
	)
	(footprint "antmicro-footprints:C_0603_1608Metric"
		(layer "F.Cu")
		(at 242.4 129.356099)
		(descr "Capacitor SMD 0603")
		(tags "capacitor 0603")
		(property "Reference" "C179"
			(at -4.416258 0.393901 0)
			(layer "F.SilkS")
			(effects
				(font
					(size 0.7 0.7)
					(thickness 0.15)
				)
				(justify left bottom)
			)
		)
		(property "Value" "C_1u_25V_0603"
			(at -1.42757 1.770288 0)
			(layer "F.Fab")
			(effects
				(font
					(size 0.7 0.7)
					(thickness 0.15)
				)
				(justify left bottom)
			)
		)
		(property "Datasheet" "https://product.samsungsem.com/mlcc/CL10A105KA8NNN.do"
			(at 0 0 0)
			(layer "F.Fab")
			(hide yes)
			(effects
				(font
					(size 1.27 1.27)
					(thickness 0.15)
				)
			)
		)
		(property "Manufacturer" "Samsung Electro-Mechanics"
			(at 0 0 0)
			(unlocked yes)
			(layer "F.Fab")
			(hide yes)
			(effects
				(font
					(size 1 1)
					(thickness 0.15)
				)
			)
		)
		(property "MPN" "CL10A105KA8NNNC"
			(at 0 0 0)
			(unlocked yes)
			(layer "F.Fab")
			(hide yes)
			(effects
				(font
					(size 1 1)
					(thickness 0.15)
				)
			)
		)
		(property "Val" "1u"
			(at 0 0 0)
			(unlocked yes)
			(layer "F.Fab")
			(hide yes)
			(effects
				(font
					(size 1 1)
					(thickness 0.15)
				)
			)
		)
		(property "License" "Apache-2.0"
			(at 0 0 0)
			(unlocked yes)
			(layer "F.Fab")
			(hide yes)
			(effects
				(font
					(size 1 1)
					(thickness 0.15)
				)
			)
		)
		(property "Author" "Antmicro"
			(at 0 0 0)
			(unlocked yes)
			(layer "F.Fab")
			(hide yes)
			(effects
				(font
					(size 1 1)
					(thickness 0.15)
				)
			)
		)
		(property "Voltage" "25V"
			(at 0 0 0)
			(unlocked yes)
			(layer "F.Fab")
			(hide yes)
			(effects
				(font
					(size 1 1)
					(thickness 0.15)
				)
			)
		)
		(property "Dielectric" ""
			(at 0 0 0)
			(unlocked yes)
			(layer "F.Fab")
			(hide yes)
			(effects
				(font
					(size 1 1)
					(thickness 0.15)
				)
			)
		)
		(sheetname "/Supply/")
		(sheetfile "supply.kicad_sch")
		(attr smd)
		(fp_line
			(start -0.15 -0.4)
			(end 0.15 -0.4)
			(stroke
				(width 0.15)
				(type solid)
			)
			(layer "F.SilkS")
		)
		(fp_line
			(start -0.15 0.4)
			(end 0.15 0.4)
			(stroke
				(width 0.15)
				(type solid)
			)
			(layer "F.SilkS")
		)
		(fp_rect
			(start -1.25 -0.65)
			(end 1.25 0.65)
			(stroke
				(width 0.05)
				(type solid)
			)
			(fill no)
			(layer "F.CrtYd")
		)
		(fp_rect
			(start -0.8 -0.4)
			(end 0.8 0.4)
			(stroke
				(width 0.15)
				(type solid)
			)
			(fill no)
			(layer "F.Fab")
		)
		(fp_text user "License: Apache-2.0"
			(at -1.682 5.895 0)
			(layer "F.Fab")
			(effects
				(font
					(size 0.7 0.7)
					(thickness 0.15)
				)
				(justify left bottom)
			)
		)
		(fp_text user "${REFERENCE}"
			(at -1.682 3.895 0)
			(layer "F.Fab")
			(effects
				(font
					(size 0.7 0.7)
					(thickness 0.15)
				)
				(justify left bottom)
			)
		)
		(fp_text user "Author: Antmicro"
			(at -1.682 4.894 0)
			(layer "F.Fab")
			(effects
				(font
					(size 0.7 0.7)
					(thickness 0.15)
				)
				(justify left bottom)
			)
		)
		(pad "1" smd roundrect
			(at -0.7 0)
			(size 0.8 1)
			(layers "F.Cu" "F.Mask" "F.Paste")
			(roundrect_rratio 0.2)
			(net 1 "GND")
			(pintype "passive")
		)
		(pad "2" smd roundrect
			(at 0.7 0)
			(size 0.8 1)
			(layers "F.Cu" "F.Mask" "F.Paste")
			(roundrect_rratio 0.2)
			(net 35 "VDC")
			(pintype "passive")
		)
	)
	(footprint "antmicro-footprints:L_0402_1005Metric"
		(layer "F.Cu")
		(at 121.025 147.61 180)
		(descr "Inductor SMD 0402")
		(tags "Inductor SMD 0402")
		(property "Reference" "L6"
			(at -5.385 -0.465 0)
			(layer "F.SilkS")
			(effects
				(font
					(size 0.7 0.7)
					(thickness 0.15)
				)
				(justify right bottom)
			)
		)
		(property "Value" "L_20n_0.35A_0402"
			(at 0 1.4 0)
			(layer "F.Fab")
			(effects
				(font
					(size 0.7 0.7)
					(thickness 0.15)
				)
				(justify right bottom)
			)
		)
		(property "Datasheet" "https://product.tdk.com/system/files/dam/doc/product/inductor/inductor/smd/catalog/inductor_automotive_high-frequency_mlg1005s_en.pdf?ref_disty=mouser"
			(at 0 0 180)
			(layer "F.Fab")
			(hide yes)
			(effects
				(font
					(size 1.27 1.27)
					(thickness 0.15)
				)
			)
		)
		(property "Val" "20n/0.35A"
			(at 0 0 180)
			(unlocked yes)
			(layer "F.Fab")
			(hide yes)
			(effects
				(font
					(size 1 1)
					(thickness 0.15)
				)
			)
		)
		(property "Manufacturer" "TDK"
			(at 0 0 180)
			(unlocked yes)
			(layer "F.Fab")
			(hide yes)
			(effects
				(font
					(size 1 1)
					(thickness 0.15)
				)
			)
		)
		(property "MPN" "MLG1005S20NJTD25"
			(at 0 0 180)
			(unlocked yes)
			(layer "F.Fab")
			(hide yes)
			(effects
				(font
					(size 1 1)
					(thickness 0.15)
				)
			)
		)
		(property "ISat" ""
			(at 0 0 180)
			(unlocked yes)
			(layer "F.Fab")
			(hide yes)
			(effects
				(font
					(size 1 1)
					(thickness 0.15)
				)
			)
		)
		(property "IMax" "0.35 A"
			(at 0 0 180)
			(unlocked yes)
			(layer "F.Fab")
			(hide yes)
			(effects
				(font
					(size 1 1)
					(thickness 0.15)
				)
			)
		)
		(property "Size" "1.0x0.5"
			(at 0 0 180)
			(unlocked yes)
			(layer "F.Fab")
			(hide yes)
			(effects
				(font
					(size 1 1)
					(thickness 0.15)
				)
			)
		)
		(property "Author" "Antmicro"
			(at 0 0 180)
			(unlocked yes)
			(layer "F.Fab")
			(hide yes)
			(effects
				(font
					(size 1 1)
					(thickness 0.15)
				)
			)
		)
		(property "License" "Apache-2.0"
			(at 0 0 180)
			(unlocked yes)
			(layer "F.Fab")
			(hide yes)
			(effects
				(font
					(size 1 1)
					(thickness 0.15)
				)
			)
		)
		(sheetname "/HDMI + SD Card/")
		(sheetfile "hdmi-sd-card.kicad_sch")
		(attr smd)
		(fp_rect
			(start -0.925 -0.47)
			(end 0.925 0.47)
			(stroke
				(width 0.05)
				(type default)
			)
			(fill no)
			(layer "F.CrtYd")
		)
		(fp_rect
			(start -0.499 -0.249)
			(end 0.499 0.249)
			(stroke
				(width 0.15)
				(type solid)
			)
			(fill no)
			(layer "F.Fab")
		)
		(fp_text user "Author: Antmicro"
			(at -0.932 4.17 180)
			(layer "F.Fab")
			(effects
				(font
					(size 0.7 0.7)
					(thickness 0.15)
				)
				(justify left bottom)
			)
		)
		(fp_text user "License: Apache-2.0"
			(at -0.932 5.17 180)
			(layer "F.Fab")
			(effects
				(font
					(size 0.7 0.7)
					(thickness 0.15)
				)
				(justify left bottom)
			)
		)
		(fp_text user "${REFERENCE}"
			(at -0.932 3.168 180)
			(layer "F.Fab")
			(effects
				(font
					(size 0.7 0.7)
					(thickness 0.15)
				)
				(justify left bottom)
			)
		)
		(pad "1" smd roundrect
			(at -0.48 0 180)
			(size 0.59 0.64)
			(layers "F.Cu" "F.Mask" "F.Paste")
			(roundrect_rratio 0.25)
			(net 344 "/FPGA MGT Interface/HDMI_IN.D2_P")
			(pintype "passive")
		)
		(pad "2" smd roundrect
			(at 0.48 0 180)
			(size 0.59 0.64)
			(layers "F.Cu" "F.Mask" "F.Paste")
			(roundrect_rratio 0.25)
			(net 676 "Net-(L6-Pad2)")
			(pintype "passive")
		)
	)
	(footprint "antmicro-footprints:C_0805_2012Metric"
		(layer "F.Cu")
		(at 262.9055 155.371 90)
		(descr "Capacitor SMD 0805")
		(tags "capacitor SMD 0805")
		(property "Reference" "C173"
			(at -4.699 0.4905 90)
			(layer "F.SilkS")
			(effects
				(font
					(size 0.7 0.7)
					(thickness 0.15)
				)
				(justify left bottom)
			)
		)
		(property "Value" "C_22u_25V_0805"
			(at -2.055717 1.963152 90)
			(layer "F.Fab")
			(effects
				(font
					(size 0.7 0.7)
					(thickness 0.15)
				)
				(justify left bottom)
			)
		)
		(property "Datasheet" "https://product.samsungsem.com/mlcc/CL21A226MAYNNN.do"
			(at 0 0 90)
			(layer "F.Fab")
			(hide yes)
			(effects
				(font
					(size 1.27 1.27)
					(thickness 0.15)
				)
			)
		)
		(property "Manufacturer" "Samsung Electro-Mechanics"
			(at 0 0 90)
			(unlocked yes)
			(layer "F.Fab")
			(hide yes)
			(effects
				(font
					(size 1 1)
					(thickness 0.15)
				)
			)
		)
		(property "MPN" "CL21A226MAYNNNE"
			(at 0 0 90)
			(unlocked yes)
			(layer "F.Fab")
			(hide yes)
			(effects
				(font
					(size 1 1)
					(thickness 0.15)
				)
			)
		)
		(property "Val" "22u"
			(at 0 0 90)
			(unlocked yes)
			(layer "F.Fab")
			(hide yes)
			(effects
				(font
					(size 1 1)
					(thickness 0.15)
				)
			)
		)
		(property "License" "Apache-2.0"
			(at 0 0 90)
			(unlocked yes)
			(layer "F.Fab")
			(hide yes)
			(effects
				(font
					(size 1 1)
					(thickness 0.15)
				)
			)
		)
		(property "Author" "Antmicro"
			(at 0 0 90)
			(unlocked yes)
			(layer "F.Fab")
			(hide yes)
			(effects
				(font
					(size 1 1)
					(thickness 0.15)
				)
			)
		)
		(property "Voltage" "25V"
			(at 0 0 90)
			(unlocked yes)
			(layer "F.Fab")
			(hide yes)
			(effects
				(font
					(size 1 1)
					(thickness 0.15)
				)
			)
		)
		(property "Dielectric" "X5R"
			(at 0 0 90)
			(unlocked yes)
			(layer "F.Fab")
			(hide yes)
			(effects
				(font
					(size 1 1)
					(thickness 0.15)
				)
			)
		)
		(property "Public" "False"
			(at 0 0 90)
			(unlocked yes)
			(layer "F.Fab")
			(hide yes)
			(effects
				(font
					(size 1 1)
					(thickness 0.15)
				)
			)
		)
		(sheetname "/Supply/DC-DC IO/")
		(sheetfile "dc-dc-io.kicad_sch")
		(attr smd)
		(fp_line
			(start -0.3 -0.7)
			(end 0.3 -0.7)
			(stroke
				(width 0.15)
				(type solid)
			)
			(layer "F.SilkS")
		)
		(fp_line
			(start -0.3 0.7)
			(end 0.3 0.7)
			(stroke
				(width 0.15)
				(type solid)
			)
			(layer "F.SilkS")
		)
		(fp_rect
			(start 1.95 -0.9)
			(end -1.95 0.9)
			(stroke
				(width 0.05)
				(type default)
			)
			(fill no)
			(layer "F.CrtYd")
		)
		(fp_rect
			(start -0.95 -0.675)
			(end 0.95 0.675)
			(stroke
				(width 0.15)
				(type solid)
			)
			(fill no)
			(layer "F.Fab")
		)
		(fp_text user "License: Apache-2.0"
			(at -1.9 4.947 90)
			(layer "F.Fab")
			(effects
				(font
					(size 0.7 0.7)
					(thickness 0.15)
				)
				(justify left bottom)
			)
		)
		(fp_text user "Author: Antmicro"
			(at -1.9 5.947 90)
			(layer "F.Fab")
			(effects
				(font
					(size 0.7 0.7)
					(thickness 0.15)
				)
				(justify left bottom)
			)
		)
		(fp_text user "${REFERENCE}"
			(at -1.9 3.947 90)
			(layer "F.Fab")
			(effects
				(font
					(size 0.7 0.7)
					(thickness 0.15)
				)
				(justify left bottom)
			)
		)
		(pad "1" smd roundrect
			(at -1.1 0 90)
			(size 1.2 1.3)
			(layers "F.Cu" "F.Mask" "F.Paste")
			(roundrect_rratio 0.25)
			(net 1 "GND")
			(pintype "passive")
		)
		(pad "2" smd roundrect
			(at 1.1 0 90)
			(size 1.2 1.3)
			(layers "F.Cu" "F.Mask" "F.Paste")
			(roundrect_rratio 0.25)
			(net 35 "VDC")
			(pintype "passive")
		)
	)
)
